(kicad_pcb
	(version 20260206)
	(generator "pcbnew")
	(generator_version "10.0")
	(general
		(thickness 1.6)
		(legacy_teardrops no)
	)
	(paper "A4")
	(title_block
		(title "Bryce Canyon_IOM_IOC_16318-2_OCP.brd")
		(comment 1 "Bryce Canyon / footprints 331-337 of 1605")
	)
	(layers
		(0 "F.Cu" signal "TOP")
		(4 "In1.Cu" signal "L2GND")
		(6 "In2.Cu" signal "L3")
		(8 "In3.Cu" signal "L4VCC")
		(10 "In4.Cu" signal "L5VCC")
		(12 "In5.Cu" signal "L6")
		(14 "In6.Cu" signal "L7GND")
		(2 "B.Cu" signal "BOTTOM")
		(9 "F.Adhes" user "F.Adhesive")
		(11 "B.Adhes" user "B.Adhesive")
		(13 "F.Paste" user "Package Geometry/Pastemask Top")
		(15 "B.Paste" user "Package Geometry/Pastemask Bottom")
		(5 "F.SilkS" user "Ref Des/Silkscreen Top")
		(7 "B.SilkS" user "Ref Des/Silkscreen Bottom")
		(1 "F.Mask" user "Board Geometry/Soldermask Top")
		(3 "B.Mask" user "Board Geometry/Soldermask Bottom")
		(17 "Dwgs.User" user "User.Drawings")
		(19 "Cmts.User" user "User.Comments")
		(21 "Eco1.User" user "User.Eco1")
		(23 "Eco2.User" user "User.Eco2")
		(25 "Edge.Cuts" user "Board Geometry/Outline")
		(27 "Margin" user)
		(31 "F.CrtYd" user "Package Geometry/Place Bound Top")
		(29 "B.CrtYd" user "Package Geometry/Place Bound Bottom")
		(35 "F.Fab" user "Ref Des/Assembly Top")
		(33 "B.Fab" user "Ref Des/Assembly Bottom")
	)
	(footprint ""
		(layer "F.Cu")
		(at 63.3476 -145.669 90)
		(property "Reference" "R182"
			(at 0 0 90)
			(layer "F.SilkS")
			(hide yes)
			(effects
				(font
					(size 1.27 1.27)
				)
			)
		)
		(property "Value" "2K2R2F-GP"
			(at 0.064008 -3.993896 90)
			(unlocked yes)
			(layer "F.Fab")
			(hide yes)
			(effects
				(font
					(size 1.016 1.016)
					(thickness 0.1524)
				)
			)
		)
		(property "Device Type" "R402H16"
			(at 0.064008 -5.517896 90)
			(unlocked yes)
			(layer "F.Fab")
			(hide yes)
			(effects
				(font
					(size 1.016 1.016)
					(thickness 0.1524)
				)
			)
		)
		(duplicate_pad_numbers_are_jumpers no)
		(fp_line
			(start 0.508 -0.9398)
			(end -0.508 -0.9398)
			(stroke
				(width 0.1524)
				(type default)
			)
			(layer "F.SilkS")
		)
		(fp_line
			(start -0.508 -0.9398)
			(end -0.508 0.9398)
			(stroke
				(width 0.1524)
				(type default)
			)
			(layer "F.SilkS")
		)
		(fp_rect
			(start -0.508 0.9398)
			(end 0.508 -0.9398)
			(stroke
				(width 0)
				(type default)
			)
			(fill no)
			(layer "F.CrtYd")
		)
		(fp_rect
			(start -0.508 0.9398)
			(end 0.508 -0.9398)
			(stroke
				(width 0)
				(type default)
			)
			(fill no)
			(layer "F.Fab")
		)
		(pad "1" smd custom
			(at 0 -0.4445 90)
			(size 0.1397 0.1397)
			(layers "F.Cu" "F.Mask" "F.Paste")
			(net "I2C_SCC_SDA_OUT")
			(options
				(clearance outline)
				(anchor circle)
			)
			(primitives
				(gr_poly
					(pts
						(arc
							(start -0.1778 -0.2794)
							(mid -0.249642 -0.249642)
							(end -0.2794 -0.1778)
						)
						(arc
							(start -0.2794 0.1778)
							(mid -0.249642 0.249642)
							(end -0.1778 0.2794)
						)
						(arc
							(start 0.1778 0.2794)
							(mid 0.249642 0.249642)
							(end 0.2794 0.1778)
						)
						(arc
							(start 0.2794 -0.1778)
							(mid 0.249642 -0.249642)
							(end 0.1778 -0.2794)
						)
					)
					(width 0)
					(fill yes)
				)
			)
		)
		(pad "2" smd custom
			(at 0 0.4445 90)
			(size 0.1397 0.1397)
			(layers "F.Cu" "F.Mask" "F.Paste")
			(net "P3V3_STBY")
			(options
				(clearance outline)
				(anchor circle)
			)
			(primitives
				(gr_poly
					(pts
						(arc
							(start -0.1778 -0.2794)
							(mid -0.249642 -0.249642)
							(end -0.2794 -0.1778)
						)
						(arc
							(start -0.2794 0.1778)
							(mid -0.249642 0.249642)
							(end -0.1778 0.2794)
						)
						(arc
							(start 0.1778 0.2794)
							(mid 0.249642 0.249642)
							(end 0.2794 0.1778)
						)
						(arc
							(start 0.2794 -0.1778)
							(mid 0.249642 -0.249642)
							(end 0.1778 -0.2794)
						)
					)
					(width 0)
					(fill yes)
				)
			)
		)
	)
	(footprint ""
		(layer "F.Cu")
		(at 28.790646 -176.618138 180)
		(property "Reference" "R493"
			(at 0 0 180)
			(layer "F.SilkS")
			(hide yes)
			(effects
				(font
					(size 1.27 1.27)
				)
			)
		)
		(property "Value" "100KR2F-L1-GP"
			(at 0.064008 -3.993896 180)
			(unlocked yes)
			(layer "F.Fab")
			(hide yes)
			(effects
				(font
					(size 1.016 1.016)
					(thickness 0.1524)
				)
			)
		)
		(property "Device Type" "R402H16"
			(at 0.064008 -5.517896 180)
			(unlocked yes)
			(layer "F.Fab")
			(hide yes)
			(effects
				(font
					(size 1.016 1.016)
					(thickness 0.1524)
				)
			)
		)
		(duplicate_pad_numbers_are_jumpers no)
		(fp_line
			(start 0.508 -0.9398)
			(end -0.508 -0.9398)
			(stroke
				(width 0.1524)
				(type default)
			)
			(layer "F.SilkS")
		)
		(fp_line
			(start -0.508 -0.9398)
			(end -0.508 0.9398)
			(stroke
				(width 0.1524)
				(type default)
			)
			(layer "F.SilkS")
		)
		(fp_rect
			(start -0.508 0.9398)
			(end 0.508 -0.9398)
			(stroke
				(width 0)
				(type default)
			)
			(fill no)
			(layer "F.CrtYd")
		)
		(fp_rect
			(start -0.508 0.9398)
			(end 0.508 -0.9398)
			(stroke
				(width 0)
				(type default)
			)
			(fill no)
			(layer "F.Fab")
		)
		(pad "1" smd custom
			(at 0 -0.4445 180)
			(size 0.1397 0.1397)
			(layers "F.Cu" "F.Mask" "F.Paste")
			(net "AGND_P3V3_STBY")
			(options
				(clearance outline)
				(anchor circle)
			)
			(primitives
				(gr_poly
					(pts
						(arc
							(start -0.1778 -0.2794)
							(mid -0.249642 -0.249642)
							(end -0.2794 -0.1778)
						)
						(arc
							(start -0.2794 0.1778)
							(mid -0.249642 0.249642)
							(end -0.1778 0.2794)
						)
						(arc
							(start 0.1778 0.2794)
							(mid 0.249642 0.249642)
							(end 0.2794 0.1778)
						)
						(arc
							(start 0.2794 -0.1778)
							(mid 0.249642 -0.249642)
							(end 0.1778 -0.2794)
						)
					)
					(width 0)
					(fill yes)
				)
			)
		)
		(pad "2" smd custom
			(at 0 0.4445 180)
			(size 0.1397 0.1397)
			(layers "F.Cu" "F.Mask" "F.Paste")
			(net "P3V3_STBY_MODE")
			(options
				(clearance outline)
				(anchor circle)
			)
			(primitives
				(gr_poly
					(pts
						(arc
							(start -0.1778 -0.2794)
							(mid -0.249642 -0.249642)
							(end -0.2794 -0.1778)
						)
						(arc
							(start -0.2794 0.1778)
							(mid -0.249642 0.249642)
							(end -0.1778 0.2794)
						)
						(arc
							(start 0.1778 0.2794)
							(mid 0.249642 0.249642)
							(end 0.2794 0.1778)
						)
						(arc
							(start 0.2794 -0.1778)
							(mid 0.249642 -0.249642)
							(end 0.1778 -0.2794)
						)
					)
					(width 0)
					(fill yes)
				)
			)
		)
	)
	(footprint ""
		(layer "F.Cu")
		(at 77.914754 -135.980424 -90)
		(property "Reference" "R95"
			(at 0 0 270)
			(layer "F.SilkS")
			(hide yes)
			(effects
				(font
					(size 1.27 1.27)
				)
			)
		)
		(property "Value" "0R2J-2-GP"
			(at 0.064008 -3.993896 270)
			(unlocked yes)
			(layer "F.Fab")
			(hide yes)
			(effects
				(font
					(size 1.016 1.016)
					(thickness 0.1524)
				)
			)
		)
		(property "Device Type" "R402H16"
			(at 0.064008 -5.517896 270)
			(unlocked yes)
			(layer "F.Fab")
			(hide yes)
			(effects
				(font
					(size 1.016 1.016)
					(thickness 0.1524)
				)
			)
		)
		(duplicate_pad_numbers_are_jumpers no)
		(fp_line
			(start -0.508 -0.9398)
			(end -0.508 0.9398)
			(stroke
				(width 0.1524)
				(type default)
			)
			(layer "F.SilkS")
		)
		(fp_line
			(start 0.508 -0.9398)
			(end -0.508 -0.9398)
			(stroke
				(width 0.1524)
				(type default)
			)
			(layer "F.SilkS")
		)
		(fp_rect
			(start -0.508 0.9398)
			(end 0.508 -0.9398)
			(stroke
				(width 0)
				(type default)
			)
			(fill no)
			(layer "F.CrtYd")
		)
		(fp_rect
			(start -0.508 0.9398)
			(end 0.508 -0.9398)
			(stroke
				(width 0)
				(type default)
			)
			(fill no)
			(layer "F.Fab")
		)
		(pad "1" smd custom
			(at 0 -0.4445 270)
			(size 0.1397 0.1397)
			(layers "F.Cu" "F.Mask" "F.Paste")
			(net "UART_SEL_MUX")
			(options
				(clearance outline)
				(anchor circle)
			)
			(primitives
				(gr_poly
					(pts
						(arc
							(start -0.1778 -0.2794)
							(mid -0.249642 -0.249642)
							(end -0.2794 -0.1778)
						)
						(arc
							(start -0.2794 0.1778)
							(mid -0.249642 0.249642)
							(end -0.1778 0.2794)
						)
						(arc
							(start 0.1778 0.2794)
							(mid 0.249642 0.249642)
							(end 0.2794 0.1778)
						)
						(arc
							(start 0.2794 -0.1778)
							(mid 0.249642 -0.249642)
							(end 0.1778 -0.2794)
						)
					)
					(width 0)
					(fill yes)
				)
			)
		)
		(pad "2" smd custom
			(at 0 0.4445 270)
			(size 0.1397 0.1397)
			(layers "F.Cu" "F.Mask" "F.Paste")
			(net "D_FLIP_Q#")
			(options
				(clearance outline)
				(anchor circle)
			)
			(primitives
				(gr_poly
					(pts
						(arc
							(start -0.1778 -0.2794)
							(mid -0.249642 -0.249642)
							(end -0.2794 -0.1778)
						)
						(arc
							(start -0.2794 0.1778)
							(mid -0.249642 0.249642)
							(end -0.1778 0.2794)
						)
						(arc
							(start 0.1778 0.2794)
							(mid 0.249642 0.249642)
							(end 0.2794 0.1778)
						)
						(arc
							(start 0.2794 -0.1778)
							(mid 0.249642 -0.249642)
							(end 0.1778 -0.2794)
						)
					)
					(width 0)
					(fill yes)
				)
			)
		)
	)
	(footprint ""
		(layer "F.Cu")
		(at 136.7155 -17.85366 180)
		(property "Reference" "C138"
			(at 0 0 180)
			(layer "F.SilkS")
			(hide yes)
			(effects
				(font
					(size 1.27 1.27)
				)
			)
		)
		(property "Value" "SCD1U25V2KX-2-GP"
			(at 1.1811 -2.7051 180)
			(unlocked yes)
			(layer "F.Fab")
			(hide yes)
			(effects
				(font
					(size 1.016 1.016)
					(thickness 0.1524)
				)
			)
		)
		(property "Device Type" "C402H22"
			(at 1.1811 -4.2291 180)
			(unlocked yes)
			(layer "F.Fab")
			(hide yes)
			(effects
				(font
					(size 1.016 1.016)
					(thickness 0.1524)
				)
			)
		)
		(duplicate_pad_numbers_are_jumpers no)
		(fp_rect
			(start -0.4318 0.9525)
			(end 0.4318 -0.9525)
			(stroke
				(width 0)
				(type default)
			)
			(fill no)
			(layer "F.CrtYd")
		)
		(fp_rect
			(start -0.4318 0.9525)
			(end 0.4318 -0.9525)
			(stroke
				(width 0)
				(type default)
			)
			(fill no)
			(layer "F.Fab")
		)
		(pad "1" smd custom
			(at 0 -0.4445 180)
			(size 0.1524 0.1524)
			(layers "F.Cu" "F.Mask" "F.Paste")
			(net "P12V_IOM")
			(options
				(clearance outline)
				(anchor circle)
			)
			(primitives
				(gr_poly
					(pts
						(arc
							(start 0.3048 -0.2032)
							(mid 0.275042 -0.275042)
							(end 0.2032 -0.3048)
						)
						(arc
							(start -0.2032 -0.3048)
							(mid -0.275042 -0.275042)
							(end -0.3048 -0.2032)
						)
						(arc
							(start -0.3048 0.2032)
							(mid -0.275042 0.275042)
							(end -0.2032 0.3048)
						)
						(arc
							(start 0.2032 0.3048)
							(mid 0.275042 0.275042)
							(end 0.3048 0.2032)
						)
					)
					(width 0)
					(fill yes)
				)
			)
		)
		(pad "2" smd custom
			(at 0 0.4445 180)
			(size 0.1524 0.1524)
			(layers "F.Cu" "F.Mask" "F.Paste")
			(net "GND")
			(options
				(clearance outline)
				(anchor circle)
			)
			(primitives
				(gr_poly
					(pts
						(arc
							(start 0.3048 -0.2032)
							(mid 0.275042 -0.275042)
							(end 0.2032 -0.3048)
						)
						(arc
							(start -0.2032 -0.3048)
							(mid -0.275042 -0.275042)
							(end -0.3048 -0.2032)
						)
						(arc
							(start -0.3048 0.2032)
							(mid -0.275042 0.275042)
							(end -0.2032 0.3048)
						)
						(arc
							(start 0.2032 0.3048)
							(mid 0.275042 0.275042)
							(end 0.3048 0.2032)
						)
					)
					(width 0)
					(fill yes)
				)
			)
		)
	)
	(footprint ""
		(layer "F.Cu")
		(at 83.520534 -133.682486 -90)
		(property "Reference" "R53"
			(at 0 0 270)
			(layer "F.SilkS")
			(hide yes)
			(effects
				(font
					(size 1.27 1.27)
				)
			)
		)
		(property "Value" "4K7R2F-GP"
			(at 0.064008 -3.993896 270)
			(unlocked yes)
			(layer "F.Fab")
			(hide yes)
			(effects
				(font
					(size 1.016 1.016)
					(thickness 0.1524)
				)
			)
		)
		(property "Device Type" "R402H16"
			(at 0.064008 -5.517896 270)
			(unlocked yes)
			(layer "F.Fab")
			(hide yes)
			(effects
				(font
					(size 1.016 1.016)
					(thickness 0.1524)
				)
			)
		)
		(duplicate_pad_numbers_are_jumpers no)
		(fp_line
			(start -0.508 -0.9398)
			(end -0.508 0.9398)
			(stroke
				(width 0.1524)
				(type default)
			)
			(layer "F.SilkS")
		)
		(fp_line
			(start 0.508 -0.9398)
			(end -0.508 -0.9398)
			(stroke
				(width 0.1524)
				(type default)
			)
			(layer "F.SilkS")
		)
		(fp_rect
			(start -0.508 0.9398)
			(end 0.508 -0.9398)
			(stroke
				(width 0)
				(type default)
			)
			(fill no)
			(layer "F.CrtYd")
		)
		(fp_rect
			(start -0.508 0.9398)
			(end 0.508 -0.9398)
			(stroke
				(width 0)
				(type default)
			)
			(fill no)
			(layer "F.Fab")
		)
		(pad "1" smd custom
			(at 0 -0.4445 270)
			(size 0.1397 0.1397)
			(layers "F.Cu" "F.Mask" "F.Paste")
			(net "P3V3_STBY")
			(options
				(clearance outline)
				(anchor circle)
			)
			(primitives
				(gr_poly
					(pts
						(arc
							(start -0.1778 -0.2794)
							(mid -0.249642 -0.249642)
							(end -0.2794 -0.1778)
						)
						(arc
							(start -0.2794 0.1778)
							(mid -0.249642 0.249642)
							(end -0.1778 0.2794)
						)
						(arc
							(start 0.1778 0.2794)
							(mid 0.249642 0.249642)
							(end 0.2794 0.1778)
						)
						(arc
							(start 0.2794 -0.1778)
							(mid 0.249642 -0.249642)
							(end 0.1778 -0.2794)
						)
					)
					(width 0)
					(fill yes)
				)
			)
		)
		(pad "2" smd custom
			(at 0 0.4445 270)
			(size 0.1397 0.1397)
			(layers "F.Cu" "F.Mask" "F.Paste")
			(net "I2C_DEBUG_SCL")
			(options
				(clearance outline)
				(anchor circle)
			)
			(primitives
				(gr_poly
					(pts
						(arc
							(start -0.1778 -0.2794)
							(mid -0.249642 -0.249642)
							(end -0.2794 -0.1778)
						)
						(arc
							(start -0.2794 0.1778)
							(mid -0.249642 0.249642)
							(end -0.1778 0.2794)
						)
						(arc
							(start 0.1778 0.2794)
							(mid 0.249642 0.249642)
							(end 0.2794 0.1778)
						)
						(arc
							(start 0.2794 -0.1778)
							(mid 0.249642 -0.249642)
							(end 0.1778 -0.2794)
						)
					)
					(width 0)
					(fill yes)
				)
			)
		)
	)
	(footprint ""
		(layer "F.Cu")
		(at 98.8822 -149.751034 -90)
		(property "Reference" "R30"
			(at 0 0 270)
			(layer "F.SilkS")
			(hide yes)
			(effects
				(font
					(size 1.27 1.27)
				)
			)
		)
		(property "Value" "4K7R2F-GP"
			(at 0.064008 -3.993896 270)
			(unlocked yes)
			(layer "F.Fab")
			(hide yes)
			(effects
				(font
					(size 1.016 1.016)
					(thickness 0.1524)
				)
			)
		)
		(property "Device Type" "R402H16"
			(at 0.064008 -5.517896 270)
			(unlocked yes)
			(layer "F.Fab")
			(hide yes)
			(effects
				(font
					(size 1.016 1.016)
					(thickness 0.1524)
				)
			)
		)
		(duplicate_pad_numbers_are_jumpers no)
		(fp_line
			(start -0.508 -0.9398)
			(end -0.508 0.9398)
			(stroke
				(width 0.1524)
				(type default)
			)
			(layer "F.SilkS")
		)
		(fp_line
			(start 0.508 -0.9398)
			(end -0.508 -0.9398)
			(stroke
				(width 0.1524)
				(type default)
			)
			(layer "F.SilkS")
		)
		(fp_rect
			(start -0.508 0.9398)
			(end 0.508 -0.9398)
			(stroke
				(width 0)
				(type default)
			)
			(fill no)
			(layer "F.CrtYd")
		)
		(fp_rect
			(start -0.508 0.9398)
			(end 0.508 -0.9398)
			(stroke
				(width 0)
				(type default)
			)
			(fill no)
			(layer "F.Fab")
		)
		(pad "1" smd custom
			(at 0 -0.4445 270)
			(size 0.1397 0.1397)
			(layers "F.Cu" "F.Mask" "F.Paste")
			(net "P3V3_STBY")
			(options
				(clearance outline)
				(anchor circle)
			)
			(primitives
				(gr_poly
					(pts
						(arc
							(start -0.1778 -0.2794)
							(mid -0.249642 -0.249642)
							(end -0.2794 -0.1778)
						)
						(arc
							(start -0.2794 0.1778)
							(mid -0.249642 0.249642)
							(end -0.1778 0.2794)
						)
						(arc
							(start 0.1778 0.2794)
							(mid 0.249642 0.249642)
							(end 0.2794 0.1778)
						)
						(arc
							(start 0.2794 -0.1778)
							(mid 0.249642 -0.249642)
							(end 0.1778 -0.2794)
						)
					)
					(width 0)
					(fill yes)
				)
			)
		)
		(pad "2" smd custom
			(at 0 0.4445 270)
			(size 0.1397 0.1397)
			(layers "F.Cu" "F.Mask" "F.Paste")
			(net "USB_OCS_N3")
			(options
				(clearance outline)
				(anchor circle)
			)
			(primitives
				(gr_poly
					(pts
						(arc
							(start -0.1778 -0.2794)
							(mid -0.249642 -0.249642)
							(end -0.2794 -0.1778)
						)
						(arc
							(start -0.2794 0.1778)
							(mid -0.249642 0.249642)
							(end -0.1778 0.2794)
						)
						(arc
							(start 0.1778 0.2794)
							(mid 0.249642 0.249642)
							(end 0.2794 0.1778)
						)
						(arc
							(start 0.2794 -0.1778)
							(mid 0.249642 -0.249642)
							(end 0.1778 -0.2794)
						)
					)
					(width 0)
					(fill yes)
				)
			)
		)
	)
	(footprint ""
		(layer "F.Cu")
		(at 187.57011 -88.37549 180)
		(property "Reference" "R655"
			(at 0 0 180)
			(layer "F.SilkS")
			(hide yes)
			(effects
				(font
					(size 1.27 1.27)
				)
			)
		)
		(property "Value" "10KR2F-2-GP"
			(at 0.064008 -3.993896 180)
			(unlocked yes)
			(layer "F.Fab")
			(hide yes)
			(effects
				(font
					(size 1.016 1.016)
					(thickness 0.1524)
				)
			)
		)
		(property "Device Type" "R402H16"
			(at 0.064008 -5.517896 180)
			(unlocked yes)
			(layer "F.Fab")
			(hide yes)
			(effects
				(font
					(size 1.016 1.016)
					(thickness 0.1524)
				)
			)
		)
		(duplicate_pad_numbers_are_jumpers no)
		(fp_line
			(start 0.508 -0.9398)
			(end -0.508 -0.9398)
			(stroke
				(width 0.1524)
				(type default)
			)
			(layer "F.SilkS")
		)
		(fp_line
			(start -0.508 -0.9398)
			(end -0.508 0.9398)
			(stroke
				(width 0.1524)
				(type default)
			)
			(layer "F.SilkS")
		)
		(fp_rect
			(start -0.508 0.9398)
			(end 0.508 -0.9398)
			(stroke
				(width 0)
				(type default)
			)
			(fill no)
			(layer "F.CrtYd")
		)
		(fp_rect
			(start -0.508 0.9398)
			(end 0.508 -0.9398)
			(stroke
				(width 0)
				(type default)
			)
			(fill no)
			(layer "F.Fab")
		)
		(pad "1" smd custom
			(at 0 -0.4445 180)
			(size 0.1397 0.1397)
			(layers "F.Cu" "F.Mask" "F.Paste")
			(net "SYS_DBMODE1")
			(options
				(clearance outline)
				(anchor circle)
			)
			(primitives
				(gr_poly
					(pts
						(arc
							(start -0.1778 -0.2794)
							(mid -0.249642 -0.249642)
							(end -0.2794 -0.1778)
						)
						(arc
							(start -0.2794 0.1778)
							(mid -0.249642 0.249642)
							(end -0.1778 0.2794)
						)
						(arc
							(start 0.1778 0.2794)
							(mid 0.249642 0.249642)
							(end 0.2794 0.1778)
						)
						(arc
							(start 0.2794 -0.1778)
							(mid 0.249642 -0.249642)
							(end 0.1778 -0.2794)
						)
					)
					(width 0)
					(fill yes)
				)
			)
		)
		(pad "2" smd custom
			(at 0 0.4445 180)
			(size 0.1397 0.1397)
			(layers "F.Cu" "F.Mask" "F.Paste")
			(net "GND")
			(options
				(clearance outline)
				(anchor circle)
			)
			(primitives
				(gr_poly
					(pts
						(arc
							(start -0.1778 -0.2794)
							(mid -0.249642 -0.249642)
							(end -0.2794 -0.1778)
						)
						(arc
							(start -0.2794 0.1778)
							(mid -0.249642 0.249642)
							(end -0.1778 0.2794)
						)
						(arc
							(start 0.1778 0.2794)
							(mid 0.249642 0.249642)
							(end 0.2794 0.1778)
						)
						(arc
							(start 0.2794 -0.1778)
							(mid 0.249642 -0.249642)
							(end 0.1778 -0.2794)
						)
					)
					(width 0)
					(fill yes)
				)
			)
		)
	)
)
